(kicad_pcb
	(version 20260206)
	(generator "pcbnew")
	(generator_version "10.0")
	(general
		(thickness 1.6)
		(legacy_teardrops no)
	)
	(paper "A4")
	(title_block
		(title "Bryce Canyon_SCC_16316-1_OCP.brd")
		(comment 1 "Bryce Canyon / footprints 1019-1026 of 1561")
	)
	(layers
		(0 "F.Cu" signal "TOP")
		(4 "In1.Cu" signal "L2GND")
		(6 "In2.Cu" signal "L3")
		(8 "In3.Cu" signal "L4VCC")
		(10 "In4.Cu" signal "L5VCC")
		(12 "In5.Cu" signal "L6")
		(14 "In6.Cu" signal "L7GND")
		(2 "B.Cu" signal "BOTTOM")
		(9 "F.Adhes" user "F.Adhesive")
		(11 "B.Adhes" user "B.Adhesive")
		(13 "F.Paste" user "Package Geometry/Pastemask Top")
		(15 "B.Paste" user "Package Geometry/Pastemask Bottom")
		(5 "F.SilkS" user "Ref Des/Silkscreen Top")
		(7 "B.SilkS" user "Ref Des/Silkscreen Bottom")
		(1 "F.Mask" user "Board Geometry/Soldermask Top")
		(3 "B.Mask" user "Board Geometry/Soldermask Bottom")
		(17 "Dwgs.User" user "User.Drawings")
		(19 "Cmts.User" user "User.Comments")
		(21 "Eco1.User" user "User.Eco1")
		(23 "Eco2.User" user "User.Eco2")
		(25 "Edge.Cuts" user "Board Geometry/Outline")
		(27 "Margin" user)
		(31 "F.CrtYd" user "Package Geometry/Place Bound Top")
		(29 "B.CrtYd" user "Package Geometry/Place Bound Bottom")
		(35 "F.Fab" user "Ref Des/Assembly Top")
		(33 "B.Fab" user "Ref Des/Assembly Bottom")
	)
	(footprint ""
		(layer "B.Cu")
		(at 177.799746 -33.636458)
		(property "Reference" "TP149"
			(at 0 0 0)
			(layer "B.SilkS")
			(hide yes)
			(effects
				(font
					(size 1.27 1.27)
				)
				(justify mirror)
			)
		)
		(property "Value" "TPAD28-2-GP"
			(at 0.0127 -1.6637 0)
			(unlocked yes)
			(layer "B.Fab")
			(hide yes)
			(effects
				(font
					(size 1.016 1.016)
					(thickness 0.1524)
				)
				(justify mirror)
			)
		)
		(property "Device Type" "TPAD28"
			(at 0.0127 -3.1877 0)
			(unlocked yes)
			(layer "B.Fab")
			(hide yes)
			(effects
				(font
					(size 1.016 1.016)
					(thickness 0.1524)
				)
				(justify mirror)
			)
		)
		(duplicate_pad_numbers_are_jumpers no)
		(fp_poly
			(pts
				(arc
					(start 0.3556 0)
					(mid -0.3556 0)
					(end 0.3556 0)
				)
			)
			(stroke
				(width 0)
				(type default)
			)
			(fill no)
			(layer "B.CrtYd")
		)
		(fp_poly
			(pts
				(arc
					(start 0.6096 0)
					(mid -0.6096 0)
					(end 0.6096 0)
				)
			)
			(stroke
				(width 0)
				(type default)
			)
			(fill no)
			(layer "B.Fab")
		)
		(pad "1" smd circle
			(at 0 0 180)
			(size 0.7112 0.7112)
			(layers "B.Cu" "B.Mask" "B.Paste")
			(net "SPARE5")
		)
	)
	(footprint ""
		(layer "B.Cu")
		(at 111.887 -44.2214 180)
		(property "Reference" "C68"
			(at 0 0 0)
			(layer "B.SilkS")
			(hide yes)
			(effects
				(font
					(size 1.27 1.27)
				)
				(justify mirror)
			)
		)
		(property "Value" "SCD01U16V1KX-GP"
			(at 2.8321 -1.7399 180)
			(unlocked yes)
			(layer "B.Fab")
			(hide yes)
			(effects
				(font
					(size 1.016 1.016)
					(thickness 0.1524)
				)
				(justify mirror)
			)
		)
		(property "Device Type" "C0201H13"
			(at 2.8321 -3.2639 180)
			(unlocked yes)
			(layer "B.Fab")
			(hide yes)
			(effects
				(font
					(size 1.016 1.016)
					(thickness 0.1524)
				)
				(justify mirror)
			)
		)
		(duplicate_pad_numbers_are_jumpers no)
		(fp_rect
			(start 0.2794 0.6477)
			(end -0.2794 -0.6477)
			(stroke
				(width 0)
				(type default)
			)
			(fill no)
			(layer "B.CrtYd")
		)
		(fp_rect
			(start 0.2794 0.6477)
			(end -0.2794 -0.6477)
			(stroke
				(width 0)
				(type default)
			)
			(fill no)
			(layer "B.Fab")
		)
		(pad "1" smd custom
			(at 0 -0.2794)
			(size 0.0762 0.0762)
			(layers "B.Cu" "B.Mask" "B.Paste")
			(net "PHY_DPB_TO_SCC_26_DN")
			(options
				(clearance outline)
				(anchor circle)
			)
			(primitives
				(gr_poly
					(pts
						(arc
							(start 0.1524 0.127)
							(mid 0.137521 0.162921)
							(end 0.1016 0.1778)
						)
						(arc
							(start -0.1016 0.1778)
							(mid -0.137521 0.162921)
							(end -0.1524 0.127)
						)
						(arc
							(start -0.1524 -0.127)
							(mid -0.137521 -0.162921)
							(end -0.1016 -0.1778)
						)
						(arc
							(start 0.1016 -0.1778)
							(mid 0.137521 -0.162921)
							(end 0.1524 -0.127)
						)
					)
					(width 0)
					(fill yes)
				)
			)
		)
		(pad "2" smd custom
			(at 0 0.2794)
			(size 0.0762 0.0762)
			(layers "B.Cu" "B.Mask" "B.Paste")
			(net "PHY_DPB_TO_SCC_C_26_DN")
			(options
				(clearance outline)
				(anchor circle)
			)
			(primitives
				(gr_poly
					(pts
						(arc
							(start 0.1524 0.127)
							(mid 0.137521 0.162921)
							(end 0.1016 0.1778)
						)
						(arc
							(start -0.1016 0.1778)
							(mid -0.137521 0.162921)
							(end -0.1524 0.127)
						)
						(arc
							(start -0.1524 -0.127)
							(mid -0.137521 -0.162921)
							(end -0.1016 -0.1778)
						)
						(arc
							(start 0.1016 -0.1778)
							(mid 0.137521 -0.162921)
							(end 0.1524 -0.127)
						)
					)
					(width 0)
					(fill yes)
				)
			)
		)
	)
	(footprint ""
		(layer "B.Cu")
		(at 183.4134 -35.433 -90)
		(property "Reference" "C473"
			(at 0 0 90)
			(layer "B.SilkS")
			(hide yes)
			(effects
				(font
					(size 1.27 1.27)
				)
				(justify mirror)
			)
		)
		(property "Value" "SCD1U6D3V1KX-GP"
			(at 2.8321 -1.7399 270)
			(unlocked yes)
			(layer "B.Fab")
			(hide yes)
			(effects
				(font
					(size 1.016 1.016)
					(thickness 0.1524)
				)
				(justify mirror)
			)
		)
		(property "Device Type" "C0201H13"
			(at 2.8321 -3.2639 270)
			(unlocked yes)
			(layer "B.Fab")
			(hide yes)
			(effects
				(font
					(size 1.016 1.016)
					(thickness 0.1524)
				)
				(justify mirror)
			)
		)
		(duplicate_pad_numbers_are_jumpers no)
		(fp_rect
			(start 0.2794 0.6477)
			(end -0.2794 -0.6477)
			(stroke
				(width 0)
				(type default)
			)
			(fill no)
			(layer "B.CrtYd")
		)
		(fp_rect
			(start 0.2794 0.6477)
			(end -0.2794 -0.6477)
			(stroke
				(width 0)
				(type default)
			)
			(fill no)
			(layer "B.Fab")
		)
		(pad "1" smd custom
			(at 0 -0.2794 90)
			(size 0.0762 0.0762)
			(layers "B.Cu" "B.Mask" "B.Paste")
			(net "P1V8_C")
			(options
				(clearance outline)
				(anchor circle)
			)
			(primitives
				(gr_poly
					(pts
						(arc
							(start 0.1524 0.127)
							(mid 0.137521 0.162921)
							(end 0.1016 0.1778)
						)
						(arc
							(start -0.1016 0.1778)
							(mid -0.137521 0.162921)
							(end -0.1524 0.127)
						)
						(arc
							(start -0.1524 -0.127)
							(mid -0.137521 -0.162921)
							(end -0.1016 -0.1778)
						)
						(arc
							(start 0.1016 -0.1778)
							(mid 0.137521 -0.162921)
							(end 0.1524 -0.127)
						)
					)
					(width 0)
					(fill yes)
				)
			)
		)
		(pad "2" smd custom
			(at 0 0.2794 90)
			(size 0.0762 0.0762)
			(layers "B.Cu" "B.Mask" "B.Paste")
			(net "GND")
			(options
				(clearance outline)
				(anchor circle)
			)
			(primitives
				(gr_poly
					(pts
						(arc
							(start 0.1524 0.127)
							(mid 0.137521 0.162921)
							(end 0.1016 0.1778)
						)
						(arc
							(start -0.1016 0.1778)
							(mid -0.137521 0.162921)
							(end -0.1524 0.127)
						)
						(arc
							(start -0.1524 -0.127)
							(mid -0.137521 -0.162921)
							(end -0.1016 -0.1778)
						)
						(arc
							(start 0.1016 -0.1778)
							(mid 0.137521 -0.162921)
							(end 0.1524 -0.127)
						)
					)
					(width 0)
					(fill yes)
				)
			)
		)
	)
	(footprint ""
		(layer "B.Cu")
		(at 173.7741 -43.46702 -90)
		(property "Reference" "C418"
			(at 0 0 90)
			(layer "B.SilkS")
			(hide yes)
			(effects
				(font
					(size 1.27 1.27)
				)
				(justify mirror)
			)
		)
		(property "Value" "SCD1U6D3V1KX-GP"
			(at 2.8321 -1.7399 270)
			(unlocked yes)
			(layer "B.Fab")
			(hide yes)
			(effects
				(font
					(size 1.016 1.016)
					(thickness 0.1524)
				)
				(justify mirror)
			)
		)
		(property "Device Type" "C0201H13"
			(at 2.8321 -3.2639 270)
			(unlocked yes)
			(layer "B.Fab")
			(hide yes)
			(effects
				(font
					(size 1.016 1.016)
					(thickness 0.1524)
				)
				(justify mirror)
			)
		)
		(duplicate_pad_numbers_are_jumpers no)
		(fp_rect
			(start 0.2794 0.6477)
			(end -0.2794 -0.6477)
			(stroke
				(width 0)
				(type default)
			)
			(fill no)
			(layer "B.CrtYd")
		)
		(fp_rect
			(start 0.2794 0.6477)
			(end -0.2794 -0.6477)
			(stroke
				(width 0)
				(type default)
			)
			(fill no)
			(layer "B.Fab")
		)
		(pad "1" smd custom
			(at 0 -0.2794 90)
			(size 0.0762 0.0762)
			(layers "B.Cu" "B.Mask" "B.Paste")
			(net "P0V975")
			(options
				(clearance outline)
				(anchor circle)
			)
			(primitives
				(gr_poly
					(pts
						(arc
							(start 0.1524 0.127)
							(mid 0.137521 0.162921)
							(end 0.1016 0.1778)
						)
						(arc
							(start -0.1016 0.1778)
							(mid -0.137521 0.162921)
							(end -0.1524 0.127)
						)
						(arc
							(start -0.1524 -0.127)
							(mid -0.137521 -0.162921)
							(end -0.1016 -0.1778)
						)
						(arc
							(start 0.1016 -0.1778)
							(mid 0.137521 -0.162921)
							(end 0.1524 -0.127)
						)
					)
					(width 0)
					(fill yes)
				)
			)
		)
		(pad "2" smd custom
			(at 0 0.2794 90)
			(size 0.0762 0.0762)
			(layers "B.Cu" "B.Mask" "B.Paste")
			(net "GND")
			(options
				(clearance outline)
				(anchor circle)
			)
			(primitives
				(gr_poly
					(pts
						(arc
							(start 0.1524 0.127)
							(mid 0.137521 0.162921)
							(end 0.1016 0.1778)
						)
						(arc
							(start -0.1016 0.1778)
							(mid -0.137521 0.162921)
							(end -0.1524 0.127)
						)
						(arc
							(start -0.1524 -0.127)
							(mid -0.137521 -0.162921)
							(end -0.1016 -0.1778)
						)
						(arc
							(start 0.1016 -0.1778)
							(mid 0.137521 -0.162921)
							(end 0.1524 -0.127)
						)
					)
					(width 0)
					(fill yes)
				)
			)
		)
	)
	(footprint ""
		(layer "B.Cu")
		(at 124.2441 -71.501 -90)
		(property "Reference" "C583"
			(at 0 0 90)
			(layer "B.SilkS")
			(hide yes)
			(effects
				(font
					(size 1.27 1.27)
				)
				(justify mirror)
			)
		)
		(property "Value" "SCD1U6D3V1KX-GP"
			(at 2.8321 -1.7399 270)
			(unlocked yes)
			(layer "B.Fab")
			(hide yes)
			(effects
				(font
					(size 1.016 1.016)
					(thickness 0.1524)
				)
				(justify mirror)
			)
		)
		(property "Device Type" "C0201H13"
			(at 2.8321 -3.2639 270)
			(unlocked yes)
			(layer "B.Fab")
			(hide yes)
			(effects
				(font
					(size 1.016 1.016)
					(thickness 0.1524)
				)
				(justify mirror)
			)
		)
		(duplicate_pad_numbers_are_jumpers no)
		(fp_rect
			(start 0.2794 0.6477)
			(end -0.2794 -0.6477)
			(stroke
				(width 0)
				(type default)
			)
			(fill no)
			(layer "B.CrtYd")
		)
		(fp_rect
			(start 0.2794 0.6477)
			(end -0.2794 -0.6477)
			(stroke
				(width 0)
				(type default)
			)
			(fill no)
			(layer "B.Fab")
		)
		(pad "1" smd custom
			(at 0 -0.2794 90)
			(size 0.0762 0.0762)
			(layers "B.Cu" "B.Mask" "B.Paste")
			(net "GB_VDDA")
			(options
				(clearance outline)
				(anchor circle)
			)
			(primitives
				(gr_poly
					(pts
						(arc
							(start 0.1524 0.127)
							(mid 0.137521 0.162921)
							(end 0.1016 0.1778)
						)
						(arc
							(start -0.1016 0.1778)
							(mid -0.137521 0.162921)
							(end -0.1524 0.127)
						)
						(arc
							(start -0.1524 -0.127)
							(mid -0.137521 -0.162921)
							(end -0.1016 -0.1778)
						)
						(arc
							(start 0.1016 -0.1778)
							(mid 0.137521 -0.162921)
							(end 0.1524 -0.127)
						)
					)
					(width 0)
					(fill yes)
				)
			)
		)
		(pad "2" smd custom
			(at 0 0.2794 90)
			(size 0.0762 0.0762)
			(layers "B.Cu" "B.Mask" "B.Paste")
			(net "GND")
			(options
				(clearance outline)
				(anchor circle)
			)
			(primitives
				(gr_poly
					(pts
						(arc
							(start 0.1524 0.127)
							(mid 0.137521 0.162921)
							(end 0.1016 0.1778)
						)
						(arc
							(start -0.1016 0.1778)
							(mid -0.137521 0.162921)
							(end -0.1524 0.127)
						)
						(arc
							(start -0.1524 -0.127)
							(mid -0.137521 -0.162921)
							(end -0.1016 -0.1778)
						)
						(arc
							(start 0.1016 -0.1778)
							(mid 0.137521 -0.162921)
							(end 0.1524 -0.127)
						)
					)
					(width 0)
					(fill yes)
				)
			)
		)
	)
	(footprint ""
		(layer "B.Cu")
		(at 104.495092 -58.547)
		(property "Reference" "C152"
			(at 0 0 0)
			(layer "B.SilkS")
			(hide yes)
			(effects
				(font
					(size 1.27 1.27)
				)
				(justify mirror)
			)
		)
		(property "Value" "SCD1U6D3V1KX-GP"
			(at 2.8321 -1.7399 0)
			(unlocked yes)
			(layer "B.Fab")
			(hide yes)
			(effects
				(font
					(size 1.016 1.016)
					(thickness 0.1524)
				)
				(justify mirror)
			)
		)
		(property "Device Type" "C0201H13"
			(at 2.8321 -3.2639 0)
			(unlocked yes)
			(layer "B.Fab")
			(hide yes)
			(effects
				(font
					(size 1.016 1.016)
					(thickness 0.1524)
				)
				(justify mirror)
			)
		)
		(duplicate_pad_numbers_are_jumpers no)
		(fp_rect
			(start 0.2794 0.6477)
			(end -0.2794 -0.6477)
			(stroke
				(width 0)
				(type default)
			)
			(fill no)
			(layer "B.CrtYd")
		)
		(fp_rect
			(start 0.2794 0.6477)
			(end -0.2794 -0.6477)
			(stroke
				(width 0)
				(type default)
			)
			(fill no)
			(layer "B.Fab")
		)
		(pad "1" smd custom
			(at 0 -0.2794 180)
			(size 0.0762 0.0762)
			(layers "B.Cu" "B.Mask" "B.Paste")
			(net "P1V8_E")
			(options
				(clearance outline)
				(anchor circle)
			)
			(primitives
				(gr_poly
					(pts
						(arc
							(start 0.1524 0.127)
							(mid 0.137521 0.162921)
							(end 0.1016 0.1778)
						)
						(arc
							(start -0.1016 0.1778)
							(mid -0.137521 0.162921)
							(end -0.1524 0.127)
						)
						(arc
							(start -0.1524 -0.127)
							(mid -0.137521 -0.162921)
							(end -0.1016 -0.1778)
						)
						(arc
							(start 0.1016 -0.1778)
							(mid 0.137521 -0.162921)
							(end 0.1524 -0.127)
						)
					)
					(width 0)
					(fill yes)
				)
			)
		)
		(pad "2" smd custom
			(at 0 0.2794 180)
			(size 0.0762 0.0762)
			(layers "B.Cu" "B.Mask" "B.Paste")
			(net "GND")
			(options
				(clearance outline)
				(anchor circle)
			)
			(primitives
				(gr_poly
					(pts
						(arc
							(start 0.1524 0.127)
							(mid 0.137521 0.162921)
							(end 0.1016 0.1778)
						)
						(arc
							(start -0.1016 0.1778)
							(mid -0.137521 0.162921)
							(end -0.1524 0.127)
						)
						(arc
							(start -0.1524 -0.127)
							(mid -0.137521 -0.162921)
							(end -0.1016 -0.1778)
						)
						(arc
							(start 0.1016 -0.1778)
							(mid 0.137521 -0.162921)
							(end 0.1524 -0.127)
						)
					)
					(width 0)
					(fill yes)
				)
			)
		)
	)
	(footprint ""
		(layer "B.Cu")
		(at 70.485 -62.484 90)
		(property "Reference" "R158"
			(at 0 0 90)
			(layer "B.SilkS")
			(hide yes)
			(effects
				(font
					(size 1.27 1.27)
				)
				(justify mirror)
			)
		)
		(property "Value" "D51R3F-2-GP"
			(at 0.0254 -2.5146 90)
			(unlocked yes)
			(layer "B.Fab")
			(hide yes)
			(effects
				(font
					(size 1.016 1.016)
					(thickness 0.1524)
				)
				(justify mirror)
			)
		)
		(property "Device Type" "R603H22"
			(at 0.0254 -4.0386 90)
			(unlocked yes)
			(layer "B.Fab")
			(hide yes)
			(effects
				(font
					(size 1.016 1.016)
					(thickness 0.1524)
				)
				(justify mirror)
			)
		)
		(duplicate_pad_numbers_are_jumpers no)
		(fp_line
			(start 0.4826 0)
			(end 0.2032 0)
			(stroke
				(width 0.2032)
				(type default)
			)
			(layer "B.SilkS")
		)
		(fp_line
			(start -0.2032 0)
			(end -0.4826 0)
			(stroke
				(width 0.2032)
				(type default)
			)
			(layer "B.SilkS")
		)
		(fp_rect
			(start 0.5842 1.3335)
			(end -0.5842 -1.3335)
			(stroke
				(width 0)
				(type default)
			)
			(fill no)
			(layer "B.CrtYd")
		)
		(fp_rect
			(start 0.5842 1.3335)
			(end -0.5842 -1.3335)
			(stroke
				(width 0)
				(type default)
			)
			(fill no)
			(layer "B.Fab")
		)
		(pad "1" smd custom
			(at 0 -0.762 270)
			(size 0.2159 0.2159)
			(layers "B.Cu" "B.Mask" "B.Paste")
			(net "P0V9")
			(options
				(clearance outline)
				(anchor circle)
			)
			(primitives
				(gr_poly
					(pts
						(arc
							(start -0.3302 0.4318)
							(mid -0.402042 0.402042)
							(end -0.4318 0.3302)
						)
						(arc
							(start -0.4318 -0.3302)
							(mid -0.402042 -0.402042)
							(end -0.3302 -0.4318)
						)
						(arc
							(start 0.3302 -0.4318)
							(mid 0.402042 -0.402042)
							(end 0.4318 -0.3302)
						)
						(arc
							(start 0.4318 0.3302)
							(mid 0.402042 0.402042)
							(end 0.3302 0.4318)
						)
					)
					(width 0)
					(fill yes)
				)
			)
		)
		(pad "2" smd custom
			(at 0 0.762 270)
			(size 0.2159 0.2159)
			(layers "B.Cu" "B.Mask" "B.Paste")
			(net "GB_VDDA")
			(options
				(clearance outline)
				(anchor circle)
			)
			(primitives
				(gr_poly
					(pts
						(arc
							(start -0.3302 0.4318)
							(mid -0.402042 0.402042)
							(end -0.4318 0.3302)
						)
						(arc
							(start -0.4318 -0.3302)
							(mid -0.402042 -0.402042)
							(end -0.3302 -0.4318)
						)
						(arc
							(start 0.3302 -0.4318)
							(mid 0.402042 -0.402042)
							(end 0.4318 -0.3302)
						)
						(arc
							(start 0.4318 0.3302)
							(mid 0.402042 0.402042)
							(end 0.3302 0.4318)
						)
					)
					(width 0)
					(fill yes)
				)
			)
		)
	)
	(footprint ""
		(layer "B.Cu")
		(at 122.6185 -57.4802)
		(property "Reference" "C591"
			(at 0 0 0)
			(layer "B.SilkS")
			(hide yes)
			(effects
				(font
					(size 1.27 1.27)
				)
				(justify mirror)
			)
		)
		(property "Value" "SCD1U6D3V1KX-GP"
			(at 2.8321 -1.7399 0)
			(unlocked yes)
			(layer "B.Fab")
			(hide yes)
			(effects
				(font
					(size 1.016 1.016)
					(thickness 0.1524)
				)
				(justify mirror)
			)
		)
		(property "Device Type" "C0201H13"
			(at 2.8321 -3.2639 0)
			(unlocked yes)
			(layer "B.Fab")
			(hide yes)
			(effects
				(font
					(size 1.016 1.016)
					(thickness 0.1524)
				)
				(justify mirror)
			)
		)
		(duplicate_pad_numbers_are_jumpers no)
		(fp_rect
			(start 0.2794 0.6477)
			(end -0.2794 -0.6477)
			(stroke
				(width 0)
				(type default)
			)
			(fill no)
			(layer "B.CrtYd")
		)
		(fp_rect
			(start 0.2794 0.6477)
			(end -0.2794 -0.6477)
			(stroke
				(width 0)
				(type default)
			)
			(fill no)
			(layer "B.Fab")
		)
		(pad "1" smd custom
			(at 0 -0.2794 180)
			(size 0.0762 0.0762)
			(layers "B.Cu" "B.Mask" "B.Paste")
			(net "GB_VDDA")
			(options
				(clearance outline)
				(anchor circle)
			)
			(primitives
				(gr_poly
					(pts
						(arc
							(start 0.1524 0.127)
							(mid 0.137521 0.162921)
							(end 0.1016 0.1778)
						)
						(arc
							(start -0.1016 0.1778)
							(mid -0.137521 0.162921)
							(end -0.1524 0.127)
						)
						(arc
							(start -0.1524 -0.127)
							(mid -0.137521 -0.162921)
							(end -0.1016 -0.1778)
						)
						(arc
							(start 0.1016 -0.1778)
							(mid 0.137521 -0.162921)
							(end 0.1524 -0.127)
						)
					)
					(width 0)
					(fill yes)
				)
			)
		)
		(pad "2" smd custom
			(at 0 0.2794 180)
			(size 0.0762 0.0762)
			(layers "B.Cu" "B.Mask" "B.Paste")
			(net "GND")
			(options
				(clearance outline)
				(anchor circle)
			)
			(primitives
				(gr_poly
					(pts
						(arc
							(start 0.1524 0.127)
							(mid 0.137521 0.162921)
							(end 0.1016 0.1778)
						)
						(arc
							(start -0.1016 0.1778)
							(mid -0.137521 0.162921)
							(end -0.1524 0.127)
						)
						(arc
							(start -0.1524 -0.127)
							(mid -0.137521 -0.162921)
							(end -0.1016 -0.1778)
						)
						(arc
							(start 0.1016 -0.1778)
							(mid 0.137521 -0.162921)
							(end 0.1524 -0.127)
						)
					)
					(width 0)
					(fill yes)
				)
			)
		)
	)
)
